(kicad_pcb
	(version 20260206)
	(generator "pcbnew")
	(generator_version "10.0")
	(general
		(thickness 1.6)
		(legacy_teardrops no)
	)
	(paper "A4")
	(title_block
		(title "04192023_DAF0TMB3IC0_F0TG_MB_C_brd_V02_OCP.brd")
		(comment 1 "Grand Teton / footprints 5561-5566 of 8354")
	)
	(layers
		(0 "F.Cu" signal "TOP")
		(4 "In1.Cu" signal "GND")
		(6 "In2.Cu" signal "IN1")
		(8 "In3.Cu" signal "GND1")
		(10 "In4.Cu" signal "IN2")
		(12 "In5.Cu" signal "GND2")
		(14 "In6.Cu" signal "IN3")
		(16 "In7.Cu" signal "GND3")
		(18 "In8.Cu" signal "VCC")
		(20 "In9.Cu" signal "VCC1")
		(22 "In10.Cu" signal "GND4")
		(24 "In11.Cu" signal "IN4")
		(26 "In12.Cu" signal "GND5")
		(28 "In13.Cu" signal "IN5")
		(30 "In14.Cu" signal "GND6")
		(32 "In15.Cu" signal "IN6")
		(34 "In16.Cu" signal "GND7")
		(2 "B.Cu" signal "BOTTOM")
		(9 "F.Adhes" user "F.Adhesive")
		(11 "B.Adhes" user "B.Adhesive")
		(13 "F.Paste" user "Package Geometry/Pastemask Top")
		(15 "B.Paste" user "Package Geometry/Pastemask Bottom")
		(5 "F.SilkS" user "Ref Des/Silkscreen Top")
		(7 "B.SilkS" user "Ref Des/Silkscreen Bottom")
		(1 "F.Mask" user "Board Geometry/Soldermask Top")
		(3 "B.Mask" user "Board Geometry/Soldermask Bottom")
		(17 "Dwgs.User" user "User.Drawings")
		(19 "Cmts.User" user "User.Comments")
		(21 "Eco1.User" user "User.Eco1")
		(23 "Eco2.User" user "User.Eco2")
		(25 "Edge.Cuts" user "Board Geometry/Outline")
		(27 "Margin" user)
		(31 "F.CrtYd" user "Package Geometry/Place Bound Top")
		(29 "B.CrtYd" user "Package Geometry/Place Bound Bottom")
		(35 "F.Fab" user "Ref Des/Assembly Top")
		(33 "B.Fab" user "Ref Des/Assembly Bottom")
	)
	(footprint ""
		(layer "B.Cu")
		(at 164.902388 -13.65504 90)
		(property "Reference" "R2423"
			(at 0 0 90)
			(layer "B.SilkS")
			(hide yes)
			(effects
				(font
					(size 1.27 1.27)
				)
				(justify mirror)
			)
		)
		(property "Value" ""
			(at 0 0 90)
			(layer "B.Fab")
			(effects
				(font
					(size 1.27 1.27)
				)
				(justify mirror)
			)
		)
		(duplicate_pad_numbers_are_jumpers no)
		(fp_line
			(start 0.7874 -0.4064)
			(end -0.7874 -0.4064)
			(stroke
				(width 0.1524)
				(type default)
			)
			(layer "B.SilkS")
		)
		(fp_line
			(start -0.7874 -0.4064)
			(end -0.7874 0.4064)
			(stroke
				(width 0.1524)
				(type default)
			)
			(layer "B.SilkS")
		)
		(fp_line
			(start 0.7874 0.4064)
			(end 0.7874 -0.4064)
			(stroke
				(width 0.1524)
				(type default)
			)
			(layer "B.SilkS")
		)
		(fp_line
			(start -0.7874 0.4064)
			(end 0.7874 0.4064)
			(stroke
				(width 0.1524)
				(type default)
			)
			(layer "B.SilkS")
		)
		(fp_line
			(start 0.67945 -0.305054)
			(end 0.12065 -0.305054)
			(stroke
				(width 0.1)
				(type default)
			)
			(layer "B.Fab")
		)
		(fp_line
			(start 0.12065 -0.305054)
			(end 0.12065 -0.2794)
			(stroke
				(width 0.1)
				(type default)
			)
			(layer "B.Fab")
		)
		(fp_line
			(start -0.12065 -0.3048)
			(end -0.67945 -0.3048)
			(stroke
				(width 0.1)
				(type default)
			)
			(layer "B.Fab")
		)
		(fp_line
			(start -0.67945 -0.3048)
			(end -0.67945 0.3048)
			(stroke
				(width 0.1)
				(type default)
			)
			(layer "B.Fab")
		)
		(fp_line
			(start 0.12065 -0.2794)
			(end -0.12065 -0.2794)
			(stroke
				(width 0.1)
				(type default)
			)
			(layer "B.Fab")
		)
		(fp_line
			(start -0.12065 -0.2794)
			(end -0.12065 -0.3048)
			(stroke
				(width 0.1)
				(type default)
			)
			(layer "B.Fab")
		)
		(fp_line
			(start 0.12065 0.2794)
			(end 0.12065 0.3048)
			(stroke
				(width 0.1)
				(type default)
			)
			(layer "B.Fab")
		)
		(fp_line
			(start -0.120396 0.2794)
			(end 0.12065 0.2794)
			(stroke
				(width 0.1)
				(type default)
			)
			(layer "B.Fab")
		)
		(fp_line
			(start 0.67945 0.3048)
			(end 0.67945 -0.305054)
			(stroke
				(width 0.1)
				(type default)
			)
			(layer "B.Fab")
		)
		(fp_line
			(start 0.12065 0.3048)
			(end 0.67945 0.3048)
			(stroke
				(width 0.1)
				(type default)
			)
			(layer "B.Fab")
		)
		(fp_line
			(start -0.120396 0.3048)
			(end -0.120396 0.2794)
			(stroke
				(width 0.1)
				(type default)
			)
			(layer "B.Fab")
		)
		(fp_line
			(start -0.67945 0.3048)
			(end -0.120396 0.3048)
			(stroke
				(width 0.1)
				(type default)
			)
			(layer "B.Fab")
		)
		(pad "1" smd circle
			(at 0.40005 0 270)
			(size 0 0)
			(layers "B.Cu" "B.Mask" "B.Paste")
			(net "SMB_PMBUS_3V3AUX_SCL")
		)
		(pad "2" smd circle
			(at -0.40005 0 270)
			(size 0 0)
			(layers "B.Cu" "B.Mask" "B.Paste")
			(net "SMB_PMBUS_3V3AUX_SCL_R0")
		)
	)
	(footprint ""
		(layer "B.Cu")
		(at 206.429356 -386.152136 180)
		(property "Reference" "PR2525"
			(at 0 0 0)
			(layer "B.SilkS")
			(hide yes)
			(effects
				(font
					(size 1.27 1.27)
				)
				(justify mirror)
			)
		)
		(property "Value" ""
			(at 0 0 0)
			(layer "B.Fab")
			(effects
				(font
					(size 1.27 1.27)
				)
				(justify mirror)
			)
		)
		(duplicate_pad_numbers_are_jumpers no)
		(fp_line
			(start 0.7874 0.4064)
			(end 0.7874 -0.4064)
			(stroke
				(width 0.1524)
				(type default)
			)
			(layer "B.SilkS")
		)
		(fp_line
			(start 0.7874 -0.4064)
			(end -0.7874 -0.4064)
			(stroke
				(width 0.1524)
				(type default)
			)
			(layer "B.SilkS")
		)
		(fp_line
			(start -0.7874 0.4064)
			(end 0.7874 0.4064)
			(stroke
				(width 0.1524)
				(type default)
			)
			(layer "B.SilkS")
		)
		(fp_line
			(start -0.7874 -0.4064)
			(end -0.7874 0.4064)
			(stroke
				(width 0.1524)
				(type default)
			)
			(layer "B.SilkS")
		)
		(fp_line
			(start 0.67945 0.3048)
			(end 0.67945 -0.305054)
			(stroke
				(width 0.1)
				(type default)
			)
			(layer "B.Fab")
		)
		(fp_line
			(start 0.67945 -0.305054)
			(end 0.12065 -0.305054)
			(stroke
				(width 0.1)
				(type default)
			)
			(layer "B.Fab")
		)
		(fp_line
			(start 0.12065 0.3048)
			(end 0.67945 0.3048)
			(stroke
				(width 0.1)
				(type default)
			)
			(layer "B.Fab")
		)
		(fp_line
			(start 0.12065 0.2794)
			(end 0.12065 0.3048)
			(stroke
				(width 0.1)
				(type default)
			)
			(layer "B.Fab")
		)
		(fp_line
			(start 0.12065 -0.2794)
			(end -0.12065 -0.2794)
			(stroke
				(width 0.1)
				(type default)
			)
			(layer "B.Fab")
		)
		(fp_line
			(start 0.12065 -0.305054)
			(end 0.12065 -0.2794)
			(stroke
				(width 0.1)
				(type default)
			)
			(layer "B.Fab")
		)
		(fp_line
			(start -0.120396 0.3048)
			(end -0.120396 0.2794)
			(stroke
				(width 0.1)
				(type default)
			)
			(layer "B.Fab")
		)
		(fp_line
			(start -0.120396 0.2794)
			(end 0.12065 0.2794)
			(stroke
				(width 0.1)
				(type default)
			)
			(layer "B.Fab")
		)
		(fp_line
			(start -0.12065 -0.2794)
			(end -0.12065 -0.3048)
			(stroke
				(width 0.1)
				(type default)
			)
			(layer "B.Fab")
		)
		(fp_line
			(start -0.12065 -0.3048)
			(end -0.67945 -0.3048)
			(stroke
				(width 0.1)
				(type default)
			)
			(layer "B.Fab")
		)
		(fp_line
			(start -0.67945 0.3048)
			(end -0.120396 0.3048)
			(stroke
				(width 0.1)
				(type default)
			)
			(layer "B.Fab")
		)
		(fp_line
			(start -0.67945 -0.3048)
			(end -0.67945 0.3048)
			(stroke
				(width 0.1)
				(type default)
			)
			(layer "B.Fab")
		)
		(pad "1" smd circle
			(at 0.40005 0)
			(size 0 0)
			(layers "B.Cu" "B.Mask" "B.Paste")
			(net "P12V_HSC_SENSE2_N")
		)
		(pad "2" smd circle
			(at -0.40005 0)
			(size 0 0)
			(layers "B.Cu" "B.Mask" "B.Paste")
			(net "P12V_HSC_SENSE2_R2_N")
		)
	)
	(footprint ""
		(layer "B.Cu")
		(at 217.551762 -69.483478 180)
		(property "Reference" "R75"
			(at 0 0 0)
			(layer "B.SilkS")
			(hide yes)
			(effects
				(font
					(size 1.27 1.27)
				)
				(justify mirror)
			)
		)
		(property "Value" ""
			(at 0 0 0)
			(layer "B.Fab")
			(effects
				(font
					(size 1.27 1.27)
				)
				(justify mirror)
			)
		)
		(duplicate_pad_numbers_are_jumpers no)
		(fp_line
			(start 0.7874 0.4064)
			(end 0.7874 -0.4064)
			(stroke
				(width 0.1524)
				(type default)
			)
			(layer "B.SilkS")
		)
		(fp_line
			(start 0.7874 -0.4064)
			(end -0.7874 -0.4064)
			(stroke
				(width 0.1524)
				(type default)
			)
			(layer "B.SilkS")
		)
		(fp_line
			(start -0.7874 0.4064)
			(end 0.7874 0.4064)
			(stroke
				(width 0.1524)
				(type default)
			)
			(layer "B.SilkS")
		)
		(fp_line
			(start -0.7874 -0.4064)
			(end -0.7874 0.4064)
			(stroke
				(width 0.1524)
				(type default)
			)
			(layer "B.SilkS")
		)
		(fp_line
			(start 0.67945 0.3048)
			(end 0.67945 -0.305054)
			(stroke
				(width 0.1)
				(type default)
			)
			(layer "B.Fab")
		)
		(fp_line
			(start 0.67945 -0.305054)
			(end 0.12065 -0.305054)
			(stroke
				(width 0.1)
				(type default)
			)
			(layer "B.Fab")
		)
		(fp_line
			(start 0.12065 0.3048)
			(end 0.67945 0.3048)
			(stroke
				(width 0.1)
				(type default)
			)
			(layer "B.Fab")
		)
		(fp_line
			(start 0.12065 0.2794)
			(end 0.12065 0.3048)
			(stroke
				(width 0.1)
				(type default)
			)
			(layer "B.Fab")
		)
		(fp_line
			(start 0.12065 -0.2794)
			(end -0.12065 -0.2794)
			(stroke
				(width 0.1)
				(type default)
			)
			(layer "B.Fab")
		)
		(fp_line
			(start 0.12065 -0.305054)
			(end 0.12065 -0.2794)
			(stroke
				(width 0.1)
				(type default)
			)
			(layer "B.Fab")
		)
		(fp_line
			(start -0.120396 0.3048)
			(end -0.120396 0.2794)
			(stroke
				(width 0.1)
				(type default)
			)
			(layer "B.Fab")
		)
		(fp_line
			(start -0.120396 0.2794)
			(end 0.12065 0.2794)
			(stroke
				(width 0.1)
				(type default)
			)
			(layer "B.Fab")
		)
		(fp_line
			(start -0.12065 -0.2794)
			(end -0.12065 -0.3048)
			(stroke
				(width 0.1)
				(type default)
			)
			(layer "B.Fab")
		)
		(fp_line
			(start -0.12065 -0.3048)
			(end -0.67945 -0.3048)
			(stroke
				(width 0.1)
				(type default)
			)
			(layer "B.Fab")
		)
		(fp_line
			(start -0.67945 0.3048)
			(end -0.120396 0.3048)
			(stroke
				(width 0.1)
				(type default)
			)
			(layer "B.Fab")
		)
		(fp_line
			(start -0.67945 -0.3048)
			(end -0.67945 0.3048)
			(stroke
				(width 0.1)
				(type default)
			)
			(layer "B.Fab")
		)
		(pad "1" smd circle
			(at 0.40005 0)
			(size 0 0)
			(layers "B.Cu" "B.Mask" "B.Paste")
			(net "NCSI_BMC_TXD0_R")
		)
		(pad "2" smd circle
			(at -0.40005 0)
			(size 0 0)
			(layers "B.Cu" "B.Mask" "B.Paste")
			(net "RMII_BMC_OCP_TXD_0")
		)
	)
	(footprint ""
		(layer "B.Cu")
		(at 312.990992 -398.942052 90)
		(property "Reference" "C507"
			(at 0 0 90)
			(layer "B.SilkS")
			(hide yes)
			(effects
				(font
					(size 1.27 1.27)
				)
				(justify mirror)
			)
		)
		(property "Value" ""
			(at 0 0 90)
			(layer "B.Fab")
			(effects
				(font
					(size 1.27 1.27)
				)
				(justify mirror)
			)
		)
		(duplicate_pad_numbers_are_jumpers no)
		(fp_line
			(start 0.7874 -0.4064)
			(end -0.7874 -0.4064)
			(stroke
				(width 0.1524)
				(type default)
			)
			(layer "B.SilkS")
		)
		(fp_line
			(start -0.7874 -0.4064)
			(end -0.7874 0.4064)
			(stroke
				(width 0.1524)
				(type default)
			)
			(layer "B.SilkS")
		)
		(fp_line
			(start 0.7874 0.4064)
			(end 0.7874 -0.4064)
			(stroke
				(width 0.1524)
				(type default)
			)
			(layer "B.SilkS")
		)
		(fp_line
			(start -0.7874 0.4064)
			(end 0.7874 0.4064)
			(stroke
				(width 0.1524)
				(type default)
			)
			(layer "B.SilkS")
		)
		(fp_line
			(start 0.67945 -0.305054)
			(end 0.12065 -0.305054)
			(stroke
				(width 0.1)
				(type default)
			)
			(layer "B.Fab")
		)
		(fp_line
			(start 0.12065 -0.305054)
			(end 0.12065 -0.2794)
			(stroke
				(width 0.1)
				(type default)
			)
			(layer "B.Fab")
		)
		(fp_line
			(start -0.12065 -0.3048)
			(end -0.67945 -0.3048)
			(stroke
				(width 0.1)
				(type default)
			)
			(layer "B.Fab")
		)
		(fp_line
			(start -0.67945 -0.3048)
			(end -0.67945 0.3048)
			(stroke
				(width 0.1)
				(type default)
			)
			(layer "B.Fab")
		)
		(fp_line
			(start 0.12065 -0.2794)
			(end -0.12065 -0.2794)
			(stroke
				(width 0.1)
				(type default)
			)
			(layer "B.Fab")
		)
		(fp_line
			(start -0.12065 -0.2794)
			(end -0.12065 -0.3048)
			(stroke
				(width 0.1)
				(type default)
			)
			(layer "B.Fab")
		)
		(fp_line
			(start 0.12065 0.2794)
			(end 0.12065 0.3048)
			(stroke
				(width 0.1)
				(type default)
			)
			(layer "B.Fab")
		)
		(fp_line
			(start -0.120396 0.2794)
			(end 0.12065 0.2794)
			(stroke
				(width 0.1)
				(type default)
			)
			(layer "B.Fab")
		)
		(fp_line
			(start 0.67945 0.3048)
			(end 0.67945 -0.305054)
			(stroke
				(width 0.1)
				(type default)
			)
			(layer "B.Fab")
		)
		(fp_line
			(start 0.12065 0.3048)
			(end 0.67945 0.3048)
			(stroke
				(width 0.1)
				(type default)
			)
			(layer "B.Fab")
		)
		(fp_line
			(start -0.120396 0.3048)
			(end -0.120396 0.2794)
			(stroke
				(width 0.1)
				(type default)
			)
			(layer "B.Fab")
		)
		(fp_line
			(start -0.67945 0.3048)
			(end -0.120396 0.3048)
			(stroke
				(width 0.1)
				(type default)
			)
			(layer "B.Fab")
		)
		(pad "1" smd circle
			(at 0.40005 0 270)
			(size 0 0)
			(layers "B.Cu" "B.Mask" "B.Paste")
			(net "P1V8_CPU0_RT0_1A")
		)
		(pad "2" smd circle
			(at -0.40005 0 270)
			(size 0 0)
			(layers "B.Cu" "B.Mask" "B.Paste")
			(net "GND")
		)
	)
	(footprint ""
		(layer "B.Cu")
		(at 401.619974 -349.217742 -90)
		(property "Reference" "R6124"
			(at 0 0 90)
			(layer "B.SilkS")
			(hide yes)
			(effects
				(font
					(size 1.27 1.27)
				)
				(justify mirror)
			)
		)
		(property "Value" ""
			(at 0 0 90)
			(layer "B.Fab")
			(effects
				(font
					(size 1.27 1.27)
				)
				(justify mirror)
			)
		)
		(duplicate_pad_numbers_are_jumpers no)
		(fp_line
			(start -0.7874 0.4064)
			(end 0.7874 0.4064)
			(stroke
				(width 0.1524)
				(type default)
			)
			(layer "B.SilkS")
		)
		(fp_line
			(start 0.7874 0.4064)
			(end 0.7874 -0.4064)
			(stroke
				(width 0.1524)
				(type default)
			)
			(layer "B.SilkS")
		)
		(fp_line
			(start -0.7874 -0.4064)
			(end -0.7874 0.4064)
			(stroke
				(width 0.1524)
				(type default)
			)
			(layer "B.SilkS")
		)
		(fp_line
			(start 0.7874 -0.4064)
			(end -0.7874 -0.4064)
			(stroke
				(width 0.1524)
				(type default)
			)
			(layer "B.SilkS")
		)
		(fp_line
			(start -0.67945 0.3048)
			(end -0.120396 0.3048)
			(stroke
				(width 0.1)
				(type default)
			)
			(layer "B.Fab")
		)
		(fp_line
			(start -0.120396 0.3048)
			(end -0.120396 0.2794)
			(stroke
				(width 0.1)
				(type default)
			)
			(layer "B.Fab")
		)
		(fp_line
			(start 0.12065 0.3048)
			(end 0.67945 0.3048)
			(stroke
				(width 0.1)
				(type default)
			)
			(layer "B.Fab")
		)
		(fp_line
			(start 0.67945 0.3048)
			(end 0.67945 -0.305054)
			(stroke
				(width 0.1)
				(type default)
			)
			(layer "B.Fab")
		)
		(fp_line
			(start -0.120396 0.2794)
			(end 0.12065 0.2794)
			(stroke
				(width 0.1)
				(type default)
			)
			(layer "B.Fab")
		)
		(fp_line
			(start 0.12065 0.2794)
			(end 0.12065 0.3048)
			(stroke
				(width 0.1)
				(type default)
			)
			(layer "B.Fab")
		)
		(fp_line
			(start -0.12065 -0.2794)
			(end -0.12065 -0.3048)
			(stroke
				(width 0.1)
				(type default)
			)
			(layer "B.Fab")
		)
		(fp_line
			(start 0.12065 -0.2794)
			(end -0.12065 -0.2794)
			(stroke
				(width 0.1)
				(type default)
			)
			(layer "B.Fab")
		)
		(fp_line
			(start -0.67945 -0.3048)
			(end -0.67945 0.3048)
			(stroke
				(width 0.1)
				(type default)
			)
			(layer "B.Fab")
		)
		(fp_line
			(start -0.12065 -0.3048)
			(end -0.67945 -0.3048)
			(stroke
				(width 0.1)
				(type default)
			)
			(layer "B.Fab")
		)
		(fp_line
			(start 0.12065 -0.305054)
			(end 0.12065 -0.2794)
			(stroke
				(width 0.1)
				(type default)
			)
			(layer "B.Fab")
		)
		(fp_line
			(start 0.67945 -0.305054)
			(end 0.12065 -0.305054)
			(stroke
				(width 0.1)
				(type default)
			)
			(layer "B.Fab")
		)
		(pad "1" smd circle
			(at 0.40005 0 90)
			(size 0 0)
			(layers "B.Cu" "B.Mask" "B.Paste")
			(net "PVDD18_S5_P0")
		)
		(pad "2" smd circle
			(at -0.40005 0 90)
			(size 0 0)
			(layers "B.Cu" "B.Mask" "B.Paste")
			(net "FM_BOARD_SKU_ID0")
		)
	)
	(footprint ""
		(layer "B.Cu")
		(at 304.419 -360.426 180)
		(property "Reference" "R8070"
			(at 0 0 0)
			(layer "B.SilkS")
			(hide yes)
			(effects
				(font
					(size 1.27 1.27)
				)
				(justify mirror)
			)
		)
		(property "Value" ""
			(at 0 0 0)
			(layer "B.Fab")
			(effects
				(font
					(size 1.27 1.27)
				)
				(justify mirror)
			)
		)
		(duplicate_pad_numbers_are_jumpers no)
		(fp_line
			(start 0.7874 0.4064)
			(end 0.7874 -0.4064)
			(stroke
				(width 0.1524)
				(type default)
			)
			(layer "B.SilkS")
		)
		(fp_line
			(start 0.7874 -0.4064)
			(end -0.7874 -0.4064)
			(stroke
				(width 0.1524)
				(type default)
			)
			(layer "B.SilkS")
		)
		(fp_line
			(start -0.7874 0.4064)
			(end 0.7874 0.4064)
			(stroke
				(width 0.1524)
				(type default)
			)
			(layer "B.SilkS")
		)
		(fp_line
			(start -0.7874 -0.4064)
			(end -0.7874 0.4064)
			(stroke
				(width 0.1524)
				(type default)
			)
			(layer "B.SilkS")
		)
		(fp_line
			(start 0.67945 0.3048)
			(end 0.67945 -0.305054)
			(stroke
				(width 0.1)
				(type default)
			)
			(layer "B.Fab")
		)
		(fp_line
			(start 0.67945 -0.305054)
			(end 0.12065 -0.305054)
			(stroke
				(width 0.1)
				(type default)
			)
			(layer "B.Fab")
		)
		(fp_line
			(start 0.12065 0.3048)
			(end 0.67945 0.3048)
			(stroke
				(width 0.1)
				(type default)
			)
			(layer "B.Fab")
		)
		(fp_line
			(start 0.12065 0.2794)
			(end 0.12065 0.3048)
			(stroke
				(width 0.1)
				(type default)
			)
			(layer "B.Fab")
		)
		(fp_line
			(start 0.12065 -0.2794)
			(end -0.12065 -0.2794)
			(stroke
				(width 0.1)
				(type default)
			)
			(layer "B.Fab")
		)
		(fp_line
			(start 0.12065 -0.305054)
			(end 0.12065 -0.2794)
			(stroke
				(width 0.1)
				(type default)
			)
			(layer "B.Fab")
		)
		(fp_line
			(start -0.120396 0.3048)
			(end -0.120396 0.2794)
			(stroke
				(width 0.1)
				(type default)
			)
			(layer "B.Fab")
		)
		(fp_line
			(start -0.120396 0.2794)
			(end 0.12065 0.2794)
			(stroke
				(width 0.1)
				(type default)
			)
			(layer "B.Fab")
		)
		(fp_line
			(start -0.12065 -0.2794)
			(end -0.12065 -0.3048)
			(stroke
				(width 0.1)
				(type default)
			)
			(layer "B.Fab")
		)
		(fp_line
			(start -0.12065 -0.3048)
			(end -0.67945 -0.3048)
			(stroke
				(width 0.1)
				(type default)
			)
			(layer "B.Fab")
		)
		(fp_line
			(start -0.67945 0.3048)
			(end -0.120396 0.3048)
			(stroke
				(width 0.1)
				(type default)
			)
			(layer "B.Fab")
		)
		(fp_line
			(start -0.67945 -0.3048)
			(end -0.67945 0.3048)
			(stroke
				(width 0.1)
				(type default)
			)
			(layer "B.Fab")
		)
		(pad "1" smd circle
			(at 0.40005 0)
			(size 0 0)
			(layers "B.Cu" "B.Mask" "B.Paste")
			(net "PVDD18_S5_P0")
		)
		(pad "2" smd circle
			(at -0.40005 0)
			(size 0 0)
			(layers "B.Cu" "B.Mask" "B.Paste")
			(net "PVDDCR_CPU1_P0_RESET_N_R")
		)
	)
)
